# BASEBOARD_FAB2 (Tioga Pass) — schematic netlist excerpt (pin names and nets, part order shuffled) for the footprints in the layout excerpt that follows; sources: Cadence DE-HDL packaged netlist, KiCad conversion of Wiwynn_Tioga_Pass_MB.brd

J1E1  FCI-CONN12-2R-GP  pkg CONN-G5  page 195
  \1_1\  = P12V_PSU
  \1_2\  = P12V_PSU
  \1_3\  = P12V_PSU
  \2_1\  = P12V_PSU
  \2_2\  = P12V_PSU
  \2_3\  = P12V_PSU
  \3_1\  = GND
  \3_2\  = GND
  \3_3\  = GND
  \4_1\  = GND
  \4_2\  = GND
  \4_3\  = GND
  NP1  = NC

(kicad_pcb
	(version 20260206)
	(generator "pcbnew")
	(generator_version "10.0")
	(general
		(thickness 1.6)
		(legacy_teardrops no)
	)
	(paper "A4")
	(title_block
		(title "Wiwynn_Tioga_Pass_MB.brd")
		(comment 1 "Tioga Pass / footprint 2326 of 4770 (J1E1), pads 1-13 of 13")
	)
	(layers
		(0 "F.Cu" signal "TOP")
		(4 "In1.Cu" signal "L2GND")
		(6 "In2.Cu" signal "L3")
		(8 "In3.Cu" signal "L4GND")
		(10 "In4.Cu" signal "L5")
		(12 "In5.Cu" signal "L6GND")
		(14 "In6.Cu" signal "L7VCC")
		(16 "In7.Cu" signal "L8VCC")
		(18 "In8.Cu" signal "L9GND")
		(20 "In9.Cu" signal "L10")
		(22 "In10.Cu" signal "L11GND")
		(24 "In11.Cu" signal "L12")
		(26 "In12.Cu" signal "L13GND")
		(2 "B.Cu" signal "BOTTOM")
		(9 "F.Adhes" user "F.Adhesive")
		(11 "B.Adhes" user "B.Adhesive")
		(13 "F.Paste" user "Package Geometry/Pastemask Top")
		(15 "B.Paste" user "Package Geometry/Pastemask Bottom")
		(5 "F.SilkS" user "Ref Des/Silkscreen Top")
		(7 "B.SilkS" user "Ref Des/Silkscreen Bottom")
		(1 "F.Mask" user "Board Geometry/Soldermask Top")
		(3 "B.Mask" user "Board Geometry/Soldermask Bottom")
		(17 "Dwgs.User" user "User.Drawings")
		(19 "Cmts.User" user "User.Comments")
		(21 "Eco1.User" user "User.Eco1")
		(23 "Eco2.User" user "User.Eco2")
		(25 "Edge.Cuts" user "Board Geometry/Outline")
		(27 "Margin" user)
		(31 "F.CrtYd" user "Package Geometry/Place Bound Top")
		(29 "B.CrtYd" user "Package Geometry/Place Bound Bottom")
		(35 "F.Fab" user "Ref Des/Assembly Top")
		(33 "B.Fab" user "Ref Des/Assembly Bottom")
	)
	(footprint ""
		(layer "F.Cu")
		(at -1.999996 -54.909974 -90)
		(property "Reference" "J1E1"
			(at 0 0 270)
			(layer "F.SilkS")
			(hide yes)
			(effects
				(font
					(size 1.27 1.27)
				)
			)
		)
		(property "Value" "*"
			(at -18.3388 15.2273 270)
			(unlocked yes)
			(layer "F.Fab")
			(hide yes)
			(effects
				(font
					(size 1.27 1.016)
					(thickness 0.1524)
				)
			)
		)
		(property "Device Type" "FCI-CONN12-2R-GP_CONN-G5-FCI-CA"
			(at -18.3388 13.7033 270)
			(unlocked yes)
			(layer "F.Fab")
			(hide yes)
			(effects
				(font
					(size 1.27 1.016)
					(thickness 0.1524)
				)
			)
		)
		(duplicate_pad_numbers_are_jumpers no)
		(pad "" np_thru_hole circle
			(at 0 0 270)
			(size 0.254 0.254)
			(drill 2.1336)
			(layers "*.Cu" "*.Mask")
			(clearance 1.2954)
			(thermal_gap 1.2954)
		)
		(pad "1_1" thru_hole circle
			(at 2.999994 -6.999986 270)
			(size 1.1176 1.1176)
			(drill 0.749808)
			(layers "*.Cu" "*.Mask")
			(remove_unused_layers no)
			(net "P12V_PSU")
			(clearance 0.1778)
			(thermal_gap 0.1778)
		)
		(pad "1_2" thru_hole circle
			(at 2.999994 -8.999982 270)
			(size 1.1176 1.1176)
			(drill 0.749808)
			(layers "*.Cu" "*.Mask")
			(remove_unused_layers no)
			(net "P12V_PSU")
			(clearance 0.1778)
			(thermal_gap 0.1778)
		)
		(pad "1_3" thru_hole circle
			(at 2.999994 -10.999978 270)
			(size 1.1176 1.1176)
			(drill 0.749808)
			(layers "*.Cu" "*.Mask")
			(remove_unused_layers no)
			(net "P12V_PSU")
			(clearance 0.1778)
			(thermal_gap 0.1778)
		)
		(pad "2_1" thru_hole circle
			(at -2.999994 -6.999986 270)
			(size 1.1176 1.1176)
			(drill 0.749808)
			(layers "*.Cu" "*.Mask")
			(remove_unused_layers no)
			(net "P12V_PSU")
			(clearance 0.1778)
			(thermal_gap 0.1778)
		)
		(pad "2_2" thru_hole circle
			(at -2.999994 -8.999982 270)
			(size 1.1176 1.1176)
			(drill 0.749808)
			(layers "*.Cu" "*.Mask")
			(remove_unused_layers no)
			(net "P12V_PSU")
			(clearance 0.1778)
			(thermal_gap 0.1778)
		)
		(pad "2_3" thru_hole circle
			(at -2.999994 -10.999978 270)
			(size 1.1176 1.1176)
			(drill 0.749808)
			(layers "*.Cu" "*.Mask")
			(remove_unused_layers no)
			(net "P12V_PSU")
			(clearance 0.1778)
			(thermal_gap 0.1778)
		)
		(pad "3_1" thru_hole circle
			(at -2.999994 0.999998 270)
			(size 1.1176 1.1176)
			(drill 0.749808)
			(layers "*.Cu" "*.Mask")
			(remove_unused_layers no)
			(net "GND")
			(clearance 0.1778)
			(thermal_gap 0.1778)
		)
		(pad "3_2" thru_hole circle
			(at -2.999994 -0.999998 270)
			(size 1.1176 1.1176)
			(drill 0.749808)
			(layers "*.Cu" "*.Mask")
			(remove_unused_layers no)
			(net "GND")
			(clearance 0.1778)
			(thermal_gap 0.1778)
		)
		(pad "3_3" thru_hole circle
			(at -2.999994 -2.999994 270)
			(size 1.1176 1.1176)
			(drill 0.749808)
			(layers "*.Cu" "*.Mask")
			(remove_unused_layers no)
			(net "GND")
			(clearance 0.1778)
			(thermal_gap 0.1778)
		)
		(pad "4_1" thru_hole circle
			(at 2.999994 0.999998 270)
			(size 1.1176 1.1176)
			(drill 0.749808)
			(layers "*.Cu" "*.Mask")
			(remove_unused_layers no)
			(net "GND")
			(clearance 0.1778)
			(thermal_gap 0.1778)
		)
		(pad "4_2" thru_hole circle
			(at 2.999994 -0.999998 270)
			(size 1.1176 1.1176)
			(drill 0.749808)
			(layers "*.Cu" "*.Mask")
			(remove_unused_layers no)
			(net "GND")
			(clearance 0.1778)
			(thermal_gap 0.1778)
		)
		(pad "4_3" thru_hole circle
			(at 2.999994 -2.999994 270)
			(size 1.1176 1.1176)
			(drill 0.749808)
			(layers "*.Cu" "*.Mask")
			(remove_unused_layers no)
			(net "GND")
			(clearance 0.1778)
			(thermal_gap 0.1778)
		)
	)
)
